# T6G (Grand Teton) — schematic netlist excerpt (pin names and nets, part order shuffled) for the footprints in the layout excerpt that follows; sources: Cadence DE-HDL packaged netlist, KiCad conversion of 04192023_DAF0TMB3IC0_F0TG_MB_C_brd_V02_OCP.brd

R1628  Q_RES  1K 1% CHIP  pkg 0402LF  page 172 : A = PVDD18_S5_P0 ; B = HDT_HDR_TDO
R937  Q_RES  0 5% CHIP  pkg 0402LF  page 81 : A = FM_BIOS_POST_CMPLT_BUF_R_N ; B = FM_BIOS_POST_CMPLT_BUF_N

(kicad_pcb
	(version 20260206)
	(generator "pcbnew")
	(generator_version "10.0")
	(general
		(thickness 1.6)
		(legacy_teardrops no)
	)
	(paper "A4")
	(title_block
		(title "04192023_DAF0TMB3IC0_F0TG_MB_C_brd_V02_OCP.brd")
		(comment 1 "Grand Teton / footprints 3434-3435 of 8354")
	)
	(layers
		(0 "F.Cu" signal "TOP")
		(4 "In1.Cu" signal "GND")
		(6 "In2.Cu" signal "IN1")
		(8 "In3.Cu" signal "GND1")
		(10 "In4.Cu" signal "IN2")
		(12 "In5.Cu" signal "GND2")
		(14 "In6.Cu" signal "IN3")
		(16 "In7.Cu" signal "GND3")
		(18 "In8.Cu" signal "VCC")
		(20 "In9.Cu" signal "VCC1")
		(22 "In10.Cu" signal "GND4")
		(24 "In11.Cu" signal "IN4")
		(26 "In12.Cu" signal "GND5")
		(28 "In13.Cu" signal "IN5")
		(30 "In14.Cu" signal "GND6")
		(32 "In15.Cu" signal "IN6")
		(34 "In16.Cu" signal "GND7")
		(2 "B.Cu" signal "BOTTOM")
		(9 "F.Adhes" user "F.Adhesive")
		(11 "B.Adhes" user "B.Adhesive")
		(13 "F.Paste" user "Package Geometry/Pastemask Top")
		(15 "B.Paste" user "Package Geometry/Pastemask Bottom")
		(5 "F.SilkS" user "Ref Des/Silkscreen Top")
		(7 "B.SilkS" user "Ref Des/Silkscreen Bottom")
		(1 "F.Mask" user "Board Geometry/Soldermask Top")
		(3 "B.Mask" user "Board Geometry/Soldermask Bottom")
		(17 "Dwgs.User" user "User.Drawings")
		(19 "Cmts.User" user "User.Comments")
		(21 "Eco1.User" user "User.Eco1")
		(23 "Eco2.User" user "User.Eco2")
		(25 "Edge.Cuts" user "Board Geometry/Outline")
		(27 "Margin" user)
		(31 "F.CrtYd" user "Package Geometry/Place Bound Top")
		(29 "B.CrtYd" user "Package Geometry/Place Bound Bottom")
		(35 "F.Fab" user "Ref Des/Assembly Top")
		(33 "B.Fab" user "Ref Des/Assembly Bottom")
	)
	(footprint ""
		(layer "F.Cu")
		(at 386.211826 -58.7375 180)
		(property "Reference" "R1628"
			(at 0 0 180)
			(layer "F.SilkS")
			(hide yes)
			(effects
				(font
					(size 1.27 1.27)
				)
			)
		)
		(property "Value" ""
			(at 0 0 180)
			(layer "F.Fab")
			(effects
				(font
					(size 1.27 1.27)
				)
			)
		)
		(duplicate_pad_numbers_are_jumpers no)
		(fp_line
			(start 0.7874 0.4064)
			(end -0.7874 0.4064)
			(stroke
				(width 0.1524)
				(type default)
			)
			(layer "F.SilkS")
		)
		(fp_line
			(start 0.7874 -0.4064)
			(end 0.7874 0.4064)
			(stroke
				(width 0.1524)
				(type default)
			)
			(layer "F.SilkS")
		)
		(fp_line
			(start -0.7874 0.4064)
			(end -0.7874 -0.4064)
			(stroke
				(width 0.1524)
				(type default)
			)
			(layer "F.SilkS")
		)
		(fp_line
			(start -0.7874 -0.4064)
			(end 0.7874 -0.4064)
			(stroke
				(width 0.1524)
				(type default)
			)
			(layer "F.SilkS")
		)
		(fp_line
			(start 0.67945 0.3048)
			(end 0.120396 0.3048)
			(stroke
				(width 0.1)
				(type default)
			)
			(layer "F.Fab")
		)
		(fp_line
			(start 0.67945 -0.3048)
			(end 0.67945 0.3048)
			(stroke
				(width 0.1)
				(type default)
			)
			(layer "F.Fab")
		)
		(fp_line
			(start 0.12065 -0.2794)
			(end 0.12065 -0.3048)
			(stroke
				(width 0.1)
				(type default)
			)
			(layer "F.Fab")
		)
		(fp_line
			(start 0.12065 -0.3048)
			(end 0.67945 -0.3048)
			(stroke
				(width 0.1)
				(type default)
			)
			(layer "F.Fab")
		)
		(fp_line
			(start 0.120396 0.3048)
			(end 0.120396 0.2794)
			(stroke
				(width 0.1)
				(type default)
			)
			(layer "F.Fab")
		)
		(fp_line
			(start 0.120396 0.2794)
			(end -0.12065 0.2794)
			(stroke
				(width 0.1)
				(type default)
			)
			(layer "F.Fab")
		)
		(fp_line
			(start -0.12065 0.3048)
			(end -0.67945 0.3048)
			(stroke
				(width 0.1)
				(type default)
			)
			(layer "F.Fab")
		)
		(fp_line
			(start -0.12065 0.2794)
			(end -0.12065 0.3048)
			(stroke
				(width 0.1)
				(type default)
			)
			(layer "F.Fab")
		)
		(fp_line
			(start -0.12065 -0.2794)
			(end 0.12065 -0.2794)
			(stroke
				(width 0.1)
				(type default)
			)
			(layer "F.Fab")
		)
		(fp_line
			(start -0.12065 -0.305054)
			(end -0.12065 -0.2794)
			(stroke
				(width 0.1)
				(type default)
			)
			(layer "F.Fab")
		)
		(fp_line
			(start -0.67945 0.3048)
			(end -0.67945 -0.305054)
			(stroke
				(width 0.1)
				(type default)
			)
			(layer "F.Fab")
		)
		(fp_line
			(start -0.67945 -0.305054)
			(end -0.12065 -0.305054)
			(stroke
				(width 0.1)
				(type default)
			)
			(layer "F.Fab")
		)
		(pad "1" smd circle
			(at -0.40005 0 180)
			(size 0 0)
			(layers "F.Cu" "F.Mask" "F.Paste")
			(net "PVDD18_S5_P0")
		)
		(pad "2" smd circle
			(at 0.40005 0 180)
			(size 0 0)
			(layers "F.Cu" "F.Mask" "F.Paste")
			(net "HDT_HDR_TDO")
		)
	)
	(footprint ""
		(layer "F.Cu")
		(at 191.135 -137.632948 90)
		(property "Reference" "R937"
			(at 0 0 90)
			(layer "F.SilkS")
			(hide yes)
			(effects
				(font
					(size 1.27 1.27)
				)
			)
		)
		(property "Value" ""
			(at 0 0 90)
			(layer "F.Fab")
			(effects
				(font
					(size 1.27 1.27)
				)
			)
		)
		(duplicate_pad_numbers_are_jumpers no)
		(fp_line
			(start 0.7874 -0.4064)
			(end 0.7874 0.4064)
			(stroke
				(width 0.1524)
				(type default)
			)
			(layer "F.SilkS")
		)
		(fp_line
			(start -0.7874 -0.4064)
			(end 0.7874 -0.4064)
			(stroke
				(width 0.1524)
				(type default)
			)
			(layer "F.SilkS")
		)
		(fp_line
			(start 0.7874 0.4064)
			(end -0.7874 0.4064)
			(stroke
				(width 0.1524)
				(type default)
			)
			(layer "F.SilkS")
		)
		(fp_line
			(start -0.7874 0.4064)
			(end -0.7874 -0.4064)
			(stroke
				(width 0.1524)
				(type default)
			)
			(layer "F.SilkS")
		)
		(fp_line
			(start -0.12065 -0.305054)
			(end -0.12065 -0.2794)
			(stroke
				(width 0.1)
				(type default)
			)
			(layer "F.Fab")
		)
		(fp_line
			(start -0.67945 -0.305054)
			(end -0.12065 -0.305054)
			(stroke
				(width 0.1)
				(type default)
			)
			(layer "F.Fab")
		)
		(fp_line
			(start 0.67945 -0.3048)
			(end 0.67945 0.3048)
			(stroke
				(width 0.1)
				(type default)
			)
			(layer "F.Fab")
		)
		(fp_line
			(start 0.12065 -0.3048)
			(end 0.67945 -0.3048)
			(stroke
				(width 0.1)
				(type default)
			)
			(layer "F.Fab")
		)
		(fp_line
			(start 0.12065 -0.2794)
			(end 0.12065 -0.3048)
			(stroke
				(width 0.1)
				(type default)
			)
			(layer "F.Fab")
		)
		(fp_line
			(start -0.12065 -0.2794)
			(end 0.12065 -0.2794)
			(stroke
				(width 0.1)
				(type default)
			)
			(layer "F.Fab")
		)
		(fp_line
			(start 0.120396 0.2794)
			(end -0.12065 0.2794)
			(stroke
				(width 0.1)
				(type default)
			)
			(layer "F.Fab")
		)
		(fp_line
			(start -0.12065 0.2794)
			(end -0.12065 0.3048)
			(stroke
				(width 0.1)
				(type default)
			)
			(layer "F.Fab")
		)
		(fp_line
			(start 0.67945 0.3048)
			(end 0.120396 0.3048)
			(stroke
				(width 0.1)
				(type default)
			)
			(layer "F.Fab")
		)
		(fp_line
			(start 0.120396 0.3048)
			(end 0.120396 0.2794)
			(stroke
				(width 0.1)
				(type default)
			)
			(layer "F.Fab")
		)
		(fp_line
			(start -0.12065 0.3048)
			(end -0.67945 0.3048)
			(stroke
				(width 0.1)
				(type default)
			)
			(layer "F.Fab")
		)
		(fp_line
			(start -0.67945 0.3048)
			(end -0.67945 -0.305054)
			(stroke
				(width 0.1)
				(type default)
			)
			(layer "F.Fab")
		)
		(pad "1" smd circle
			(at -0.40005 0 90)
			(size 0 0)
			(layers "F.Cu" "F.Mask" "F.Paste")
			(net "FM_BIOS_POST_CMPLT_BUF_R_N")
		)
		(pad "2" smd circle
			(at 0.40005 0 90)
			(size 0 0)
			(layers "F.Cu" "F.Mask" "F.Paste")
			(net "FM_BIOS_POST_CMPLT_BUF_N")
		)
	)
)
